(kicad_pcb
	(version 20260206)
	(generator "pcbnew")
	(generator_version "10.0")
	(general
		(thickness 1.6)
		(legacy_teardrops no)
	)
	(paper "A4")
	(title_block
		(title "peb — Lightning_PEB_BRD.brd")
		(comment 1 "Lightning (Wiwynn / Facebook NVMe JBOF) / footprint 1535 of 2563 (CN15), pads 77-153 of 166")
	)
	(layers
		(0 "F.Cu" signal "TOP")
		(4 "In1.Cu" signal "L2GND")
		(6 "In2.Cu" signal "L3")
		(8 "In3.Cu" signal "L4VCC")
		(10 "In4.Cu" signal "L5VCC")
		(12 "In5.Cu" signal "L6")
		(14 "In6.Cu" signal "L7GND")
		(2 "B.Cu" signal "BOTTOM")
		(9 "F.Adhes" user "F.Adhesive")
		(11 "B.Adhes" user "B.Adhesive")
		(13 "F.Paste" user "Package Geometry/Pastemask Top")
		(15 "B.Paste" user "Package Geometry/Pastemask Bottom")
		(5 "F.SilkS" user "Ref Des/Silkscreen Top")
		(7 "B.SilkS" user "Ref Des/Silkscreen Bottom")
		(1 "F.Mask" user "Board Geometry/Soldermask Top")
		(3 "B.Mask" user "Board Geometry/Soldermask Bottom")
		(17 "Dwgs.User" user "User.Drawings")
		(19 "Cmts.User" user "User.Comments")
		(21 "Eco1.User" user "User.Eco1")
		(23 "Eco2.User" user "User.Eco2")
		(25 "Edge.Cuts" user "Board Geometry/Outline")
		(27 "Margin" user)
		(31 "F.CrtYd" user "Package Geometry/Place Bound Top")
		(29 "B.CrtYd" user "Package Geometry/Place Bound Bottom")
		(35 "F.Fab" user "Ref Des/Assembly Top")
		(33 "B.Fab" user "Ref Des/Assembly Bottom")
	)
	(footprint ""
		(layer "F.Cu")
		(at 152.634442 -9.53008)
		(property "Reference" "CN15"
			(at 0 0 0)
			(layer "F.SilkS")
			(hide yes)
			(effects
				(font
					(size 1.27 1.27)
				)
			)
		)
		(property "Value" "MLX-CONN144-12R-3-GP-U2"
			(at -33.7693 -12.9032 0)
			(unlocked yes)
			(layer "F.Fab")
			(hide yes)
			(effects
				(font
					(size 1.016 1.016)
					(thickness 0.1524)
				)
			)
		)
		(property "Device Type" "PREFIT-144P-459383U2H519"
			(at -33.7693 -14.4272 0)
			(unlocked yes)
			(layer "F.Fab")
			(hide yes)
			(effects
				(font
					(size 1.016 1.016)
					(thickness 0.1524)
				)
			)
		)
		(duplicate_pad_numbers_are_jumpers no)
		(pad "CA5" thru_hole circle
			(at 5.500116 -2.999994)
			(size 0.7366 0.7366)
			(drill 0.369824)
			(layers "*.Cu" "*.Mask")
			(remove_unused_layers no)
			(net "PCIE_RX_N88")
			(clearance 0.1778)
			(thermal_gap 0.1778)
		)
		(pad "CA6" thru_hole circle
			(at 6.249924 -3.700018)
			(size 0.7366 0.7366)
			(drill 0.369824)
			(layers "*.Cu" "*.Mask")
			(remove_unused_layers no)
			(net "GND")
			(clearance 0.1778)
			(thermal_gap 0.1778)
		)
		(pad "CA7" thru_hole circle
			(at 6.999986 -4.400042)
			(size 0.7366 0.7366)
			(drill 0.369824)
			(layers "*.Cu" "*.Mask")
			(remove_unused_layers no)
			(net "PCIE_RX_P91")
			(clearance 0.1778)
			(thermal_gap 0.1778)
		)
		(pad "CA8" thru_hole circle
			(at 7.750048 -2.999994)
			(size 0.7366 0.7366)
			(drill 0.369824)
			(layers "*.Cu" "*.Mask")
			(remove_unused_layers no)
			(net "PCIE_RX_N91")
			(clearance 0.1778)
			(thermal_gap 0.1778)
		)
		(pad "CA9" thru_hole circle
			(at 8.50011 -3.700018)
			(size 0.7366 0.7366)
			(drill 0.369824)
			(layers "*.Cu" "*.Mask")
			(remove_unused_layers no)
			(net "GND")
			(clearance 0.1778)
			(thermal_gap 0.1778)
		)
		(pad "CB1" thru_hole circle
			(at 2.500122 -8.199882)
			(size 0.7366 0.7366)
			(drill 0.369824)
			(layers "*.Cu" "*.Mask")
			(remove_unused_layers no)
			(net "HOST3_RST_N_C")
			(clearance 0.1778)
			(thermal_gap 0.1778)
		)
		(pad "CB2" thru_hole circle
			(at 3.24993 -6.800088)
			(size 0.7366 0.7366)
			(drill 0.369824)
			(layers "*.Cu" "*.Mask")
			(remove_unused_layers no)
			(net "8644_SDA_R_3")
			(clearance 0.1778)
			(thermal_gap 0.1778)
		)
		(pad "CB3" thru_hole circle
			(at 3.999992 -7.500112)
			(size 0.7366 0.7366)
			(drill 0.369824)
			(layers "*.Cu" "*.Mask")
			(remove_unused_layers no)
			(net "GND")
			(clearance 0.1778)
			(thermal_gap 0.1778)
		)
		(pad "CB4" thru_hole circle
			(at 4.750054 -8.199882)
			(size 0.7366 0.7366)
			(drill 0.369824)
			(layers "*.Cu" "*.Mask")
			(remove_unused_layers no)
			(net "PCIE_RX_P89")
			(clearance 0.1778)
			(thermal_gap 0.1778)
		)
		(pad "CB5" thru_hole circle
			(at 5.500116 -6.800088)
			(size 0.7366 0.7366)
			(drill 0.369824)
			(layers "*.Cu" "*.Mask")
			(remove_unused_layers no)
			(net "PCIE_RX_N89")
			(clearance 0.1778)
			(thermal_gap 0.1778)
		)
		(pad "CB6" thru_hole circle
			(at 6.249924 -7.500112)
			(size 0.7366 0.7366)
			(drill 0.369824)
			(layers "*.Cu" "*.Mask")
			(remove_unused_layers no)
			(net "GND")
			(clearance 0.1778)
			(thermal_gap 0.1778)
		)
		(pad "CB7" thru_hole circle
			(at 6.999986 -8.199882)
			(size 0.7366 0.7366)
			(drill 0.369824)
			(layers "*.Cu" "*.Mask")
			(remove_unused_layers no)
			(net "PCIE_RX_P90")
			(clearance 0.1778)
			(thermal_gap 0.1778)
		)
		(pad "CB8" thru_hole circle
			(at 7.750048 -6.800088)
			(size 0.7366 0.7366)
			(drill 0.369824)
			(layers "*.Cu" "*.Mask")
			(remove_unused_layers no)
			(net "PCIE_RX_N90")
			(clearance 0.1778)
			(thermal_gap 0.1778)
		)
		(pad "CB9" thru_hole circle
			(at 8.50011 -7.500112)
			(size 0.7366 0.7366)
			(drill 0.369824)
			(layers "*.Cu" "*.Mask")
			(remove_unused_layers no)
			(net "GND")
			(clearance 0.1778)
			(thermal_gap 0.1778)
		)
		(pad "CC1" thru_hole circle
			(at 2.500122 -11.999976)
			(size 0.7366 0.7366)
			(drill 0.369824)
			(layers "*.Cu" "*.Mask")
			(remove_unused_layers no)
			(net "BMC_I2C3_MINI3_SCL")
			(clearance 0.1778)
			(thermal_gap 0.1778)
		)
		(pad "CC2" thru_hole circle
			(at 3.24993 -10.599928)
			(size 0.7366 0.7366)
			(drill 0.369824)
			(layers "*.Cu" "*.Mask")
			(remove_unused_layers no)
			(net "8644_CBL_PRSNT_R_3")
			(clearance 0.1778)
			(thermal_gap 0.1778)
		)
		(pad "CC3" thru_hole circle
			(at 3.999992 -11.299952)
			(size 0.7366 0.7366)
			(drill 0.369824)
			(layers "*.Cu" "*.Mask")
			(remove_unused_layers no)
			(net "GND")
			(clearance 0.1778)
			(thermal_gap 0.1778)
		)
		(pad "CC4" thru_hole circle
			(at 4.750054 -11.999976)
			(size 0.7366 0.7366)
			(drill 0.369824)
			(layers "*.Cu" "*.Mask")
			(remove_unused_layers no)
			(net "PCIE_TX_P88")
			(clearance 0.1778)
			(thermal_gap 0.1778)
		)
		(pad "CC5" thru_hole circle
			(at 5.500116 -10.599928)
			(size 0.7366 0.7366)
			(drill 0.369824)
			(layers "*.Cu" "*.Mask")
			(remove_unused_layers no)
			(net "PCIE_TX_N88")
			(clearance 0.1778)
			(thermal_gap 0.1778)
		)
		(pad "CC6" thru_hole circle
			(at 6.249924 -11.299952)
			(size 0.7366 0.7366)
			(drill 0.369824)
			(layers "*.Cu" "*.Mask")
			(remove_unused_layers no)
			(net "GND")
			(clearance 0.1778)
			(thermal_gap 0.1778)
		)
		(pad "CC7" thru_hole circle
			(at 6.999986 -11.999976)
			(size 0.7366 0.7366)
			(drill 0.369824)
			(layers "*.Cu" "*.Mask")
			(remove_unused_layers no)
			(net "PCIE_TX_P91")
			(clearance 0.1778)
			(thermal_gap 0.1778)
		)
		(pad "CC8" thru_hole circle
			(at 7.750048 -10.599928)
			(size 0.7366 0.7366)
			(drill 0.369824)
			(layers "*.Cu" "*.Mask")
			(remove_unused_layers no)
			(net "PCIE_TX_N91")
			(clearance 0.1778)
			(thermal_gap 0.1778)
		)
		(pad "CC9" thru_hole circle
			(at 8.50011 -11.299952)
			(size 0.7366 0.7366)
			(drill 0.369824)
			(layers "*.Cu" "*.Mask")
			(remove_unused_layers no)
			(net "GND")
			(clearance 0.1778)
			(thermal_gap 0.1778)
		)
		(pad "CD1" thru_hole circle
			(at 2.500122 -15.80007)
			(size 0.7366 0.7366)
			(drill 0.369824)
			(layers "*.Cu" "*.Mask")
			(remove_unused_layers no)
			(net "8644_USB_DN3")
			(clearance 0.1778)
			(thermal_gap 0.1778)
		)
		(pad "CD2" thru_hole circle
			(at 3.24993 -14.400022)
			(size 0.7366 0.7366)
			(drill 0.369824)
			(layers "*.Cu" "*.Mask")
			(remove_unused_layers no)
			(net "8644_USB_DP3")
			(clearance 0.1778)
			(thermal_gap 0.1778)
		)
		(pad "CD3" thru_hole circle
			(at 3.999992 -15.100046)
			(size 0.7366 0.7366)
			(drill 0.369824)
			(layers "*.Cu" "*.Mask")
			(remove_unused_layers no)
			(net "GND")
			(clearance 0.1778)
			(thermal_gap 0.1778)
		)
		(pad "CD4" thru_hole circle
			(at 4.750054 -15.80007)
			(size 0.7366 0.7366)
			(drill 0.369824)
			(layers "*.Cu" "*.Mask")
			(remove_unused_layers no)
			(net "PCIE_TX_P89")
			(clearance 0.1778)
			(thermal_gap 0.1778)
		)
		(pad "CD5" thru_hole circle
			(at 5.500116 -14.400022)
			(size 0.7366 0.7366)
			(drill 0.369824)
			(layers "*.Cu" "*.Mask")
			(remove_unused_layers no)
			(net "PCIE_TX_N89")
			(clearance 0.1778)
			(thermal_gap 0.1778)
		)
		(pad "CD6" thru_hole circle
			(at 6.249924 -15.100046)
			(size 0.7366 0.7366)
			(drill 0.369824)
			(layers "*.Cu" "*.Mask")
			(remove_unused_layers no)
			(net "GND")
			(clearance 0.1778)
			(thermal_gap 0.1778)
		)
		(pad "CD7" thru_hole circle
			(at 6.999986 -15.80007)
			(size 0.7366 0.7366)
			(drill 0.369824)
			(layers "*.Cu" "*.Mask")
			(remove_unused_layers no)
			(net "PCIE_TX_P90")
			(clearance 0.1778)
			(thermal_gap 0.1778)
		)
		(pad "CD8" thru_hole circle
			(at 7.750048 -14.400022)
			(size 0.7366 0.7366)
			(drill 0.369824)
			(layers "*.Cu" "*.Mask")
			(remove_unused_layers no)
			(net "PCIE_TX_N90")
			(clearance 0.1778)
			(thermal_gap 0.1778)
		)
		(pad "CD9" thru_hole circle
			(at 8.50011 -15.100046)
			(size 0.7366 0.7366)
			(drill 0.369824)
			(layers "*.Cu" "*.Mask")
			(remove_unused_layers no)
			(net "GND")
			(clearance 0.1778)
			(thermal_gap 0.1778)
		)
		(pad "DA1" thru_hole circle
			(at 13.5001 -4.400042)
			(size 0.7366 0.7366)
			(drill 0.369824)
			(layers "*.Cu" "*.Mask")
			(remove_unused_layers no)
			(net "CLK_P_4")
			(clearance 0.1778)
			(thermal_gap 0.1778)
		)
		(pad "DA2" thru_hole circle
			(at 14.249908 -2.999994)
			(size 0.7366 0.7366)
			(drill 0.369824)
			(layers "*.Cu" "*.Mask")
			(remove_unused_layers no)
			(net "CLK_N_4")
			(clearance 0.1778)
			(thermal_gap 0.1778)
		)
		(pad "DA3" thru_hole circle
			(at 14.99997 -3.700018)
			(size 0.7366 0.7366)
			(drill 0.369824)
			(layers "*.Cu" "*.Mask")
			(remove_unused_layers no)
			(net "GND")
			(clearance 0.1778)
			(thermal_gap 0.1778)
		)
		(pad "DA4" thru_hole circle
			(at 15.750032 -4.400042)
			(size 0.7366 0.7366)
			(drill 0.369824)
			(layers "*.Cu" "*.Mask")
			(remove_unused_layers no)
			(net "PCIE_RX_P92")
			(clearance 0.1778)
			(thermal_gap 0.1778)
		)
		(pad "DA5" thru_hole circle
			(at 16.500094 -2.999994)
			(size 0.7366 0.7366)
			(drill 0.369824)
			(layers "*.Cu" "*.Mask")
			(remove_unused_layers no)
			(net "PCIE_RX_N92")
			(clearance 0.1778)
			(thermal_gap 0.1778)
		)
		(pad "DA6" thru_hole circle
			(at 17.249902 -3.700018)
			(size 0.7366 0.7366)
			(drill 0.369824)
			(layers "*.Cu" "*.Mask")
			(remove_unused_layers no)
			(net "GND")
			(clearance 0.1778)
			(thermal_gap 0.1778)
		)
		(pad "DA7" thru_hole circle
			(at 17.999964 -4.400042)
			(size 0.7366 0.7366)
			(drill 0.369824)
			(layers "*.Cu" "*.Mask")
			(remove_unused_layers no)
			(net "PCIE_RX_P95")
			(clearance 0.1778)
			(thermal_gap 0.1778)
		)
		(pad "DA8" thru_hole circle
			(at 18.750026 -2.999994)
			(size 0.7366 0.7366)
			(drill 0.369824)
			(layers "*.Cu" "*.Mask")
			(remove_unused_layers no)
			(net "PCIE_RX_N95")
			(clearance 0.1778)
			(thermal_gap 0.1778)
		)
		(pad "DA9" thru_hole circle
			(at 19.500088 -3.700018)
			(size 0.7366 0.7366)
			(drill 0.369824)
			(layers "*.Cu" "*.Mask")
			(remove_unused_layers no)
			(net "GND")
			(clearance 0.1778)
			(thermal_gap 0.1778)
		)
		(pad "DB1" thru_hole circle
			(at 13.5001 -8.199882)
			(size 0.7366 0.7366)
			(drill 0.369824)
			(layers "*.Cu" "*.Mask")
			(remove_unused_layers no)
			(net "HOST4_RST_N_C")
			(clearance 0.1778)
			(thermal_gap 0.1778)
		)
		(pad "DB2" thru_hole circle
			(at 14.249908 -6.800088)
			(size 0.7366 0.7366)
			(drill 0.369824)
			(layers "*.Cu" "*.Mask")
			(remove_unused_layers no)
			(net "8644_SDA_R_4")
			(clearance 0.1778)
			(thermal_gap 0.1778)
		)
		(pad "DB3" thru_hole circle
			(at 14.99997 -7.500112)
			(size 0.7366 0.7366)
			(drill 0.369824)
			(layers "*.Cu" "*.Mask")
			(remove_unused_layers no)
			(net "GND")
			(clearance 0.1778)
			(thermal_gap 0.1778)
		)
		(pad "DB4" thru_hole circle
			(at 15.750032 -8.199882)
			(size 0.7366 0.7366)
			(drill 0.369824)
			(layers "*.Cu" "*.Mask")
			(remove_unused_layers no)
			(net "PCIE_RX_P93")
			(clearance 0.1778)
			(thermal_gap 0.1778)
		)
		(pad "DB5" thru_hole circle
			(at 16.500094 -6.800088)
			(size 0.7366 0.7366)
			(drill 0.369824)
			(layers "*.Cu" "*.Mask")
			(remove_unused_layers no)
			(net "PCIE_RX_N93")
			(clearance 0.1778)
			(thermal_gap 0.1778)
		)
		(pad "DB6" thru_hole circle
			(at 17.249902 -7.500112)
			(size 0.7366 0.7366)
			(drill 0.369824)
			(layers "*.Cu" "*.Mask")
			(remove_unused_layers no)
			(net "GND")
			(clearance 0.1778)
			(thermal_gap 0.1778)
		)
		(pad "DB7" thru_hole circle
			(at 17.999964 -8.199882)
			(size 0.7366 0.7366)
			(drill 0.369824)
			(layers "*.Cu" "*.Mask")
			(remove_unused_layers no)
			(net "PCIE_RX_P94")
			(clearance 0.1778)
			(thermal_gap 0.1778)
		)
		(pad "DB8" thru_hole circle
			(at 18.750026 -6.800088)
			(size 0.7366 0.7366)
			(drill 0.369824)
			(layers "*.Cu" "*.Mask")
			(remove_unused_layers no)
			(net "PCIE_RX_N94")
			(clearance 0.1778)
			(thermal_gap 0.1778)
		)
		(pad "DB9" thru_hole circle
			(at 19.500088 -7.500112)
			(size 0.7366 0.7366)
			(drill 0.369824)
			(layers "*.Cu" "*.Mask")
			(remove_unused_layers no)
			(net "GND")
			(clearance 0.1778)
			(thermal_gap 0.1778)
		)
		(pad "DC1" thru_hole circle
			(at 13.5001 -11.999976)
			(size 0.7366 0.7366)
			(drill 0.369824)
			(layers "*.Cu" "*.Mask")
			(remove_unused_layers no)
			(net "BMC_I2C4_MINI4_SCL")
			(clearance 0.1778)
			(thermal_gap 0.1778)
		)
		(pad "DC2" thru_hole circle
			(at 14.249908 -10.599928)
			(size 0.7366 0.7366)
			(drill 0.369824)
			(layers "*.Cu" "*.Mask")
			(remove_unused_layers no)
			(net "8644_CBL_PRSNT_R_4")
			(clearance 0.1778)
			(thermal_gap 0.1778)
		)
		(pad "DC3" thru_hole circle
			(at 14.99997 -11.299952)
			(size 0.7366 0.7366)
			(drill 0.369824)
			(layers "*.Cu" "*.Mask")
			(remove_unused_layers no)
			(net "GND")
			(clearance 0.1778)
			(thermal_gap 0.1778)
		)
		(pad "DC4" thru_hole circle
			(at 15.750032 -11.999976)
			(size 0.7366 0.7366)
			(drill 0.369824)
			(layers "*.Cu" "*.Mask")
			(remove_unused_layers no)
			(net "PCIE_TX_P92")
			(clearance 0.1778)
			(thermal_gap 0.1778)
		)
		(pad "DC5" thru_hole circle
			(at 16.500094 -10.599928)
			(size 0.7366 0.7366)
			(drill 0.369824)
			(layers "*.Cu" "*.Mask")
			(remove_unused_layers no)
			(net "PCIE_TX_N92")
			(clearance 0.1778)
			(thermal_gap 0.1778)
		)
		(pad "DC6" thru_hole circle
			(at 17.249902 -11.299952)
			(size 0.7366 0.7366)
			(drill 0.369824)
			(layers "*.Cu" "*.Mask")
			(remove_unused_layers no)
			(net "GND")
			(clearance 0.1778)
			(thermal_gap 0.1778)
		)
		(pad "DC7" thru_hole circle
			(at 17.999964 -11.999976)
			(size 0.7366 0.7366)
			(drill 0.369824)
			(layers "*.Cu" "*.Mask")
			(remove_unused_layers no)
			(net "PCIE_TX_P95")
			(clearance 0.1778)
			(thermal_gap 0.1778)
		)
		(pad "DC8" thru_hole circle
			(at 18.750026 -10.599928)
			(size 0.7366 0.7366)
			(drill 0.369824)
			(layers "*.Cu" "*.Mask")
			(remove_unused_layers no)
			(net "PCIE_TX_N95")
			(clearance 0.1778)
			(thermal_gap 0.1778)
		)
		(pad "DC9" thru_hole circle
			(at 19.500088 -11.299952)
			(size 0.7366 0.7366)
			(drill 0.369824)
			(layers "*.Cu" "*.Mask")
			(remove_unused_layers no)
			(net "GND")
			(clearance 0.1778)
			(thermal_gap 0.1778)
		)
		(pad "DD1" thru_hole circle
			(at 13.5001 -15.80007)
			(size 0.7366 0.7366)
			(drill 0.369824)
			(layers "*.Cu" "*.Mask")
			(remove_unused_layers no)
			(net "8644_USB_DN4")
			(clearance 0.1778)
			(thermal_gap 0.1778)
		)
		(pad "DD2" thru_hole circle
			(at 14.249908 -14.400022)
			(size 0.7366 0.7366)
			(drill 0.369824)
			(layers "*.Cu" "*.Mask")
			(remove_unused_layers no)
			(net "8644_USB_DP4")
			(clearance 0.1778)
			(thermal_gap 0.1778)
		)
		(pad "DD3" thru_hole circle
			(at 14.99997 -15.100046)
			(size 0.7366 0.7366)
			(drill 0.369824)
			(layers "*.Cu" "*.Mask")
			(remove_unused_layers no)
			(net "GND")
			(clearance 0.1778)
			(thermal_gap 0.1778)
		)
		(pad "DD4" thru_hole circle
			(at 15.750032 -15.80007)
			(size 0.7366 0.7366)
			(drill 0.369824)
			(layers "*.Cu" "*.Mask")
			(remove_unused_layers no)
			(net "PCIE_TX_P93")
			(clearance 0.1778)
			(thermal_gap 0.1778)
		)
		(pad "DD5" thru_hole circle
			(at 16.500094 -14.400022)
			(size 0.7366 0.7366)
			(drill 0.369824)
			(layers "*.Cu" "*.Mask")
			(remove_unused_layers no)
			(net "PCIE_TX_N93")
			(clearance 0.1778)
			(thermal_gap 0.1778)
		)
		(pad "DD6" thru_hole circle
			(at 17.249902 -15.100046)
			(size 0.7366 0.7366)
			(drill 0.369824)
			(layers "*.Cu" "*.Mask")
			(remove_unused_layers no)
			(net "GND")
			(clearance 0.1778)
			(thermal_gap 0.1778)
		)
		(pad "DD7" thru_hole circle
			(at 17.999964 -15.80007)
			(size 0.7366 0.7366)
			(drill 0.369824)
			(layers "*.Cu" "*.Mask")
			(remove_unused_layers no)
			(net "PCIE_TX_P94")
			(clearance 0.1778)
			(thermal_gap 0.1778)
		)
		(pad "DD8" thru_hole circle
			(at 18.750026 -14.400022)
			(size 0.7366 0.7366)
			(drill 0.369824)
			(layers "*.Cu" "*.Mask")
			(remove_unused_layers no)
			(net "PCIE_TX_N94")
			(clearance 0.1778)
			(thermal_gap 0.1778)
		)
		(pad "DD9" thru_hole circle
			(at 19.500088 -15.100046)
			(size 0.7366 0.7366)
			(drill 0.369824)
			(layers "*.Cu" "*.Mask")
			(remove_unused_layers no)
			(net "GND")
			(clearance 0.1778)
			(thermal_gap 0.1778)
		)
		(pad "PTH1" thru_hole circle
			(at -21.999956 -3.700018)
			(size 0.9144 0.9144)
			(drill 0.569976)
			(layers "*.Cu" "*.Mask")
			(remove_unused_layers no)
			(net "GND")
			(clearance 0.1905)
			(thermal_gap 0.1905)
		)
		(pad "PTH2" thru_hole circle
			(at -17.999964 -17.509998)
			(size 0.9144 0.9144)
			(drill 0.569976)
			(layers "*.Cu" "*.Mask")
			(remove_unused_layers no)
			(net "GND")
			(clearance 0.1905)
			(thermal_gap 0.1905)
		)
		(pad "PTH3" thru_hole circle
			(at -13.5001 -17.509998)
			(size 0.9144 0.9144)
			(drill 0.569976)
			(layers "*.Cu" "*.Mask")
			(remove_unused_layers no)
			(net "GND")
			(clearance 0.1905)
			(thermal_gap 0.1905)
		)
		(pad "PTH4" thru_hole circle
			(at -6.999986 -17.509998)
			(size 0.9144 0.9144)
			(drill 0.569976)
			(layers "*.Cu" "*.Mask")
			(remove_unused_layers no)
			(net "GND")
			(clearance 0.1905)
			(thermal_gap 0.1905)
		)
		(pad "PTH5" thru_hole circle
			(at -2.500122 -17.509998)
			(size 0.9144 0.9144)
			(drill 0.569976)
			(layers "*.Cu" "*.Mask")
			(remove_unused_layers no)
			(net "GND")
			(clearance 0.1905)
			(thermal_gap 0.1905)
		)
		(pad "PTH6" thru_hole circle
			(at 3.999992 -17.509998)
			(size 0.9144 0.9144)
			(drill 0.569976)
			(layers "*.Cu" "*.Mask")
			(remove_unused_layers no)
			(net "GND")
			(clearance 0.1905)
			(thermal_gap 0.1905)
		)
		(pad "PTH7" thru_hole circle
			(at 8.50011 -17.509998)
			(size 0.9144 0.9144)
			(drill 0.569976)
			(layers "*.Cu" "*.Mask")
			(remove_unused_layers no)
			(net "GND")
			(clearance 0.1905)
			(thermal_gap 0.1905)
		)
		(pad "PTH8" thru_hole circle
			(at 14.99997 -17.509998)
			(size 0.9144 0.9144)
			(drill 0.569976)
			(layers "*.Cu" "*.Mask")
			(remove_unused_layers no)
			(net "GND")
			(clearance 0.1905)
			(thermal_gap 0.1905)
		)
		(pad "PTH9" thru_hole circle
			(at 19.500088 -17.509998)
			(size 0.9144 0.9144)
			(drill 0.569976)
			(layers "*.Cu" "*.Mask")
			(remove_unused_layers no)
			(net "GND")
			(clearance 0.1905)
			(thermal_gap 0.1905)
		)
	)
)
